# S9S_MB_2U (Grand Teton) — schematic netlist excerpt (pin names and nets, part order shuffled) for the footprints in the layout excerpt that follows; sources: Cadence DE-HDL packaged netlist, KiCad conversion of 03242023_DA0F0TMBIJ0_F0T_Motherboard_J_brd_V01_OCP.brd

C22  Q_CAP  10UF 16V 10% X6S  pkg C0805  page 88 : A = P12V_S3_AUX_CPU0_NVDIMM ; B = GND
R93  Q_RES  240 1% EMPTY  pkg 0402LF  page 126 : A = PVNN_TERM_CPU1 ; B = PU_CPU1_UPI3_AC_COUPLING
R23  Q_RES  100 1% CHIP  pkg 0402LF  page 16 : A = DBP_CPU0_MBP1_GTL_R_N ; B = DBP_CPU_MBP1_GTL_N

(kicad_pcb
	(version 20260206)
	(generator "pcbnew")
	(generator_version "10.0")
	(general
		(thickness 1.6)
		(legacy_teardrops no)
	)
	(paper "A4")
	(title_block
		(title "03242023_DA0F0TMBIJ0_F0T_Motherboard_J_brd_V01_OCP.brd")
		(comment 1 "Grand Teton / footprints 5767-5769 of 6105")
	)
	(layers
		(0 "F.Cu" signal "TOP")
		(4 "In1.Cu" signal "GND")
		(6 "In2.Cu" signal "IN1")
		(8 "In3.Cu" signal "GND1")
		(10 "In4.Cu" signal "IN2")
		(12 "In5.Cu" signal "GND2")
		(14 "In6.Cu" signal "IN3")
		(16 "In7.Cu" signal "GND3")
		(18 "In8.Cu" signal "VCC")
		(20 "In9.Cu" signal "VCC1")
		(22 "In10.Cu" signal "GND4")
		(24 "In11.Cu" signal "IN4")
		(26 "In12.Cu" signal "GND5")
		(28 "In13.Cu" signal "IN5")
		(30 "In14.Cu" signal "GND6")
		(32 "In15.Cu" signal "IN6")
		(34 "In16.Cu" signal "GND7")
		(2 "B.Cu" signal "BOTTOM")
		(9 "F.Adhes" user "F.Adhesive")
		(11 "B.Adhes" user "B.Adhesive")
		(13 "F.Paste" user "Package Geometry/Pastemask Top")
		(15 "B.Paste" user "Package Geometry/Pastemask Bottom")
		(5 "F.SilkS" user "Ref Des/Silkscreen Top")
		(7 "B.SilkS" user "Ref Des/Silkscreen Bottom")
		(1 "F.Mask" user "Board Geometry/Soldermask Top")
		(3 "B.Mask" user "Board Geometry/Soldermask Bottom")
		(17 "Dwgs.User" user "User.Drawings")
		(19 "Cmts.User" user "User.Comments")
		(21 "Eco1.User" user "User.Eco1")
		(23 "Eco2.User" user "User.Eco2")
		(25 "Edge.Cuts" user "Board Geometry/Outline")
		(27 "Margin" user)
		(31 "F.CrtYd" user "Package Geometry/Place Bound Top")
		(29 "B.CrtYd" user "Package Geometry/Place Bound Bottom")
		(35 "F.Fab" user "Ref Des/Assembly Top")
		(33 "B.Fab" user "Ref Des/Assembly Bottom")
	)
	(footprint ""
		(layer "B.Cu")
		(at 179.168552 -192.699894 -90)
		(property "Reference" "R93"
			(at 0 0 90)
			(layer "B.SilkS")
			(hide yes)
			(effects
				(font
					(size 1.27 1.27)
				)
				(justify mirror)
			)
		)
		(property "Value" ""
			(at 0 0 90)
			(layer "B.Fab")
			(effects
				(font
					(size 1.27 1.27)
				)
				(justify mirror)
			)
		)
		(duplicate_pad_numbers_are_jumpers no)
		(fp_line
			(start -0.7874 0.4064)
			(end 0.7874 0.4064)
			(stroke
				(width 0.1524)
				(type default)
			)
			(layer "B.SilkS")
		)
		(fp_line
			(start 0.7874 0.4064)
			(end 0.7874 -0.4064)
			(stroke
				(width 0.1524)
				(type default)
			)
			(layer "B.SilkS")
		)
		(fp_line
			(start -0.7874 -0.4064)
			(end -0.7874 0.4064)
			(stroke
				(width 0.1524)
				(type default)
			)
			(layer "B.SilkS")
		)
		(fp_line
			(start 0.7874 -0.4064)
			(end -0.7874 -0.4064)
			(stroke
				(width 0.1524)
				(type default)
			)
			(layer "B.SilkS")
		)
		(fp_line
			(start -0.67945 0.3048)
			(end -0.120396 0.3048)
			(stroke
				(width 0.1)
				(type default)
			)
			(layer "B.Fab")
		)
		(fp_line
			(start -0.120396 0.3048)
			(end -0.120396 0.2794)
			(stroke
				(width 0.1)
				(type default)
			)
			(layer "B.Fab")
		)
		(fp_line
			(start 0.12065 0.3048)
			(end 0.67945 0.3048)
			(stroke
				(width 0.1)
				(type default)
			)
			(layer "B.Fab")
		)
		(fp_line
			(start 0.67945 0.3048)
			(end 0.67945 -0.305054)
			(stroke
				(width 0.1)
				(type default)
			)
			(layer "B.Fab")
		)
		(fp_line
			(start -0.120396 0.2794)
			(end 0.12065 0.2794)
			(stroke
				(width 0.1)
				(type default)
			)
			(layer "B.Fab")
		)
		(fp_line
			(start 0.12065 0.2794)
			(end 0.12065 0.3048)
			(stroke
				(width 0.1)
				(type default)
			)
			(layer "B.Fab")
		)
		(fp_line
			(start -0.12065 -0.2794)
			(end -0.12065 -0.3048)
			(stroke
				(width 0.1)
				(type default)
			)
			(layer "B.Fab")
		)
		(fp_line
			(start 0.12065 -0.2794)
			(end -0.12065 -0.2794)
			(stroke
				(width 0.1)
				(type default)
			)
			(layer "B.Fab")
		)
		(fp_line
			(start -0.67945 -0.3048)
			(end -0.67945 0.3048)
			(stroke
				(width 0.1)
				(type default)
			)
			(layer "B.Fab")
		)
		(fp_line
			(start -0.12065 -0.3048)
			(end -0.67945 -0.3048)
			(stroke
				(width 0.1)
				(type default)
			)
			(layer "B.Fab")
		)
		(fp_line
			(start 0.12065 -0.305054)
			(end 0.12065 -0.2794)
			(stroke
				(width 0.1)
				(type default)
			)
			(layer "B.Fab")
		)
		(fp_line
			(start 0.67945 -0.305054)
			(end 0.12065 -0.305054)
			(stroke
				(width 0.1)
				(type default)
			)
			(layer "B.Fab")
		)
		(pad "1" smd circle
			(at 0.40005 0 90)
			(size 0 0)
			(layers "B.Cu" "B.Mask" "B.Paste")
			(net "PVNN_TERM_CPU1")
		)
		(pad "2" smd circle
			(at -0.40005 0 90)
			(size 0 0)
			(layers "B.Cu" "B.Mask" "B.Paste")
			(net "PU_CPU1_UPI3_AC_COUPLING")
		)
	)
	(footprint ""
		(layer "B.Cu")
		(at 335.288128 -190.82893 90)
		(property "Reference" "R23"
			(at 0 0 90)
			(layer "B.SilkS")
			(hide yes)
			(effects
				(font
					(size 1.27 1.27)
				)
				(justify mirror)
			)
		)
		(property "Value" ""
			(at 0 0 90)
			(layer "B.Fab")
			(effects
				(font
					(size 1.27 1.27)
				)
				(justify mirror)
			)
		)
		(duplicate_pad_numbers_are_jumpers no)
		(fp_line
			(start 0.7874 -0.4064)
			(end -0.7874 -0.4064)
			(stroke
				(width 0.1524)
				(type default)
			)
			(layer "B.SilkS")
		)
		(fp_line
			(start -0.7874 -0.4064)
			(end -0.7874 0.4064)
			(stroke
				(width 0.1524)
				(type default)
			)
			(layer "B.SilkS")
		)
		(fp_line
			(start 0.7874 0.4064)
			(end 0.7874 -0.4064)
			(stroke
				(width 0.1524)
				(type default)
			)
			(layer "B.SilkS")
		)
		(fp_line
			(start -0.7874 0.4064)
			(end 0.7874 0.4064)
			(stroke
				(width 0.1524)
				(type default)
			)
			(layer "B.SilkS")
		)
		(fp_line
			(start 0.67945 -0.305054)
			(end 0.12065 -0.305054)
			(stroke
				(width 0.1)
				(type default)
			)
			(layer "B.Fab")
		)
		(fp_line
			(start 0.12065 -0.305054)
			(end 0.12065 -0.2794)
			(stroke
				(width 0.1)
				(type default)
			)
			(layer "B.Fab")
		)
		(fp_line
			(start -0.12065 -0.3048)
			(end -0.67945 -0.3048)
			(stroke
				(width 0.1)
				(type default)
			)
			(layer "B.Fab")
		)
		(fp_line
			(start -0.67945 -0.3048)
			(end -0.67945 0.3048)
			(stroke
				(width 0.1)
				(type default)
			)
			(layer "B.Fab")
		)
		(fp_line
			(start 0.12065 -0.2794)
			(end -0.12065 -0.2794)
			(stroke
				(width 0.1)
				(type default)
			)
			(layer "B.Fab")
		)
		(fp_line
			(start -0.12065 -0.2794)
			(end -0.12065 -0.3048)
			(stroke
				(width 0.1)
				(type default)
			)
			(layer "B.Fab")
		)
		(fp_line
			(start 0.12065 0.2794)
			(end 0.12065 0.3048)
			(stroke
				(width 0.1)
				(type default)
			)
			(layer "B.Fab")
		)
		(fp_line
			(start -0.120396 0.2794)
			(end 0.12065 0.2794)
			(stroke
				(width 0.1)
				(type default)
			)
			(layer "B.Fab")
		)
		(fp_line
			(start 0.67945 0.3048)
			(end 0.67945 -0.305054)
			(stroke
				(width 0.1)
				(type default)
			)
			(layer "B.Fab")
		)
		(fp_line
			(start 0.12065 0.3048)
			(end 0.67945 0.3048)
			(stroke
				(width 0.1)
				(type default)
			)
			(layer "B.Fab")
		)
		(fp_line
			(start -0.120396 0.3048)
			(end -0.120396 0.2794)
			(stroke
				(width 0.1)
				(type default)
			)
			(layer "B.Fab")
		)
		(fp_line
			(start -0.67945 0.3048)
			(end -0.120396 0.3048)
			(stroke
				(width 0.1)
				(type default)
			)
			(layer "B.Fab")
		)
		(pad "1" smd circle
			(at 0.40005 0 270)
			(size 0 0)
			(layers "B.Cu" "B.Mask" "B.Paste")
			(net "DBP_CPU0_MBP1_GTL_R_N")
		)
		(pad "2" smd circle
			(at -0.40005 0 270)
			(size 0 0)
			(layers "B.Cu" "B.Mask" "B.Paste")
			(net "DBP_CPU_MBP1_GTL_N")
		)
	)
	(footprint ""
		(layer "B.Cu")
		(at 258.023614 -321.524376 -90)
		(property "Reference" "C22"
			(at 0 0 90)
			(layer "B.SilkS")
			(hide yes)
			(effects
				(font
					(size 1.27 1.27)
				)
				(justify mirror)
			)
		)
		(property "Value" ""
			(at 0 0 90)
			(layer "B.Fab")
			(effects
				(font
					(size 1.27 1.27)
				)
				(justify mirror)
			)
		)
		(duplicate_pad_numbers_are_jumpers no)
		(fp_line
			(start -1.524 0.762)
			(end 1.524 0.762)
			(stroke
				(width 0.1524)
				(type default)
			)
			(layer "B.SilkS")
		)
		(fp_line
			(start 1.524 0.762)
			(end 1.524 -0.762)
			(stroke
				(width 0.1524)
				(type default)
			)
			(layer "B.SilkS")
		)
		(fp_line
			(start -1.524 -0.762)
			(end -1.524 0.762)
			(stroke
				(width 0.1524)
				(type default)
			)
			(layer "B.SilkS")
		)
		(fp_line
			(start 1.524 -0.762)
			(end -1.524 -0.762)
			(stroke
				(width 0.1524)
				(type default)
			)
			(layer "B.SilkS")
		)
		(fp_line
			(start -1.1049 0.724916)
			(end -1.1049 -0.724916)
			(stroke
				(width 0.1)
				(type default)
			)
			(layer "B.Fab")
		)
		(fp_line
			(start 1.1049 0.724916)
			(end -1.1049 0.724916)
			(stroke
				(width 0.1)
				(type default)
			)
			(layer "B.Fab")
		)
		(fp_line
			(start -1.1049 -0.724916)
			(end 1.1049 -0.724916)
			(stroke
				(width 0.1)
				(type default)
			)
			(layer "B.Fab")
		)
		(fp_line
			(start 1.1049 -0.724916)
			(end 1.1049 0.724916)
			(stroke
				(width 0.1)
				(type default)
			)
			(layer "B.Fab")
		)
		(pad "1" smd rect
			(at 0.889 0 270)
			(size 1.016 1.27)
			(layers "B.Cu" "B.Mask" "B.Paste")
			(net "P12V_S3_AUX_CPU0_NVDIMM")
		)
		(pad "2" smd rect
			(at -0.889 0 270)
			(size 1.016 1.27)
			(layers "B.Cu" "B.Mask" "B.Paste")
			(net "GND")
		)
	)
)
